(kicad_pcb
	(version 20240108)
	(generator "pcbnew")
	(generator_version "8.0")
	(general
		(thickness 1.62)
		(legacy_teardrops no)
	)
	(paper "A4")
	(title_block
		(title "Jetson Orin Baseboard")
		(date "2025-03-12")
		(rev "1.3.4")
		(company "Antmicro Ltd")
		(comment 1 "www.antmicro.com")
		(comment 9 "footprint 675 of 677 (U6), pads 71-78 of 78")
	)
	(layers
		(0 "F.Cu" signal)
		(1 "In1.Cu" signal)
		(2 "In2.Cu" signal)
		(3 "In3.Cu" signal)
		(4 "In4.Cu" jumper)
		(5 "In5.Cu" signal)
		(6 "In6.Cu" signal)
		(31 "B.Cu" signal)
		(32 "B.Adhes" user "B.Adhesive")
		(33 "F.Adhes" user "F.Adhesive")
		(34 "B.Paste" user)
		(35 "F.Paste" user)
		(36 "B.SilkS" user "B.Silkscreen")
		(37 "F.SilkS" user "F.Silkscreen")
		(38 "B.Mask" user)
		(39 "F.Mask" user)
		(40 "Dwgs.User" user "User.Drawings")
		(41 "Cmts.User" user "User.Comments")
		(42 "Eco1.User" user "User.Eco1")
		(43 "Eco2.User" user "User.Eco2")
		(44 "Edge.Cuts" user)
		(45 "Margin" user)
		(46 "B.CrtYd" user "B.Courtyard")
		(47 "F.CrtYd" user "F.Courtyard")
		(48 "B.Fab" user)
		(49 "F.Fab" user)
	)
	(footprint "antmicro-footprints:IC_TPS65987DDHRSHR"
		(layer "B.Cu")
		(at 66.3 103.1 90)
		(property "Reference" "U6"
			(at -1.8 4.7 -90)
			(layer "B.SilkS")
			(effects
				(font
					(size 0.7 0.7)
					(thickness 0.15)
				)
				(justify left bottom mirror)
			)
		)
		(property "Value" "TPS65988DHRSHR"
			(at 0 -4.9 -90)
			(layer "B.Fab")
			(effects
				(font
					(size 0.7 0.7)
					(thickness 0.15)
				)
				(justify left bottom mirror)
			)
		)
		(property "Footprint" "antmicro-footprints:IC_TPS65987DDHRSHR"
			(at 0 0 90)
			(layer "F.Fab")
			(hide yes)
			(effects
				(font
					(size 1.27 1.27)
					(thickness 0.15)
				)
			)
		)
		(property "Datasheet" "https://www.ti.com/lit/ds/symlink/tps65988.pdf?ts=1662726631004&ref_url=https%253A%252F%252Fwww.ti.com%252Fproduct%252FTPS65988"
			(at 0 0 90)
			(layer "F.Fab")
			(hide yes)
			(effects
				(font
					(size 1.27 1.27)
					(thickness 0.15)
				)
			)
		)
		(property "Author" "Antmicro"
			(at 169.4 36.8 0)
			(layer "B.Fab")
			(hide yes)
			(effects
				(font
					(size 1 1)
					(thickness 0.15)
				)
				(justify mirror)
			)
		)
		(property "License" "Apache-2.0"
			(at 169.4 36.8 0)
			(layer "B.Fab")
			(hide yes)
			(effects
				(font
					(size 1 1)
					(thickness 0.15)
				)
				(justify mirror)
			)
		)
		(property "MPN" "TPS65988DHRSHR "
			(at 169.4 36.8 0)
			(layer "B.Fab")
			(hide yes)
			(effects
				(font
					(size 1 1)
					(thickness 0.15)
				)
				(justify mirror)
			)
		)
		(property "Manufacturer" "Texas Instruments"
			(at 169.4 36.8 0)
			(layer "B.Fab")
			(hide yes)
			(effects
				(font
					(size 1 1)
					(thickness 0.15)
				)
				(justify mirror)
			)
		)
		(sheetname "USB Debug, DP")
		(sheetfile "usb.kicad_sch")
		(attr smd)
		(pad "59" thru_hole circle
			(at 1.048 -1.322 90)
			(size 0.45 0.45)
			(drill 0.1)
			(layers "*.Cu")
			(remove_unused_layers no)
			(net 1 "GND")
			(pinfunction "GND_EP")
			(pintype "power_in")
		)
		(pad "59" thru_hole circle
			(at 1.048 1.327 90)
			(size 0.45 0.45)
			(drill 0.1)
			(layers "*.Cu")
			(remove_unused_layers no)
			(net 1 "GND")
			(pinfunction "GND_EP")
			(pintype "power_in")
		)
		(pad "59" thru_hole circle
			(at 1.048 2.504 90)
			(size 0.45 0.45)
			(drill 0.1)
			(layers "*.Cu")
			(remove_unused_layers no)
			(net 1 "GND")
			(pinfunction "GND_EP")
			(pintype "power_in")
		)
		(pad "59" thru_hole circle
			(at 1.05 0 90)
			(size 0.45 0.45)
			(drill 0.1)
			(layers "*.Cu")
			(remove_unused_layers no)
			(net 1 "GND")
			(pinfunction "GND_EP")
			(pintype "power_in")
		)
		(pad "59" smd roundrect
			(at 1.05 0)
			(size 5.5 3.4)
			(layers "B.Cu" "B.Mask")
			(roundrect_rratio 0.02941176471)
			(net 1 "GND")
			(pinfunction "GND_EP")
			(pintype "power_in")
			(solder_mask_margin 0.05)
		)
		(pad "59" thru_hole circle
			(at 2.248 -1.322 90)
			(size 0.45 0.45)
			(drill 0.1)
			(layers "*.Cu")
			(remove_unused_layers no)
			(net 1 "GND")
			(pinfunction "GND_EP")
			(pintype "power_in")
		)
		(pad "59" thru_hole circle
			(at 2.248 0.001 90)
			(size 0.45 0.45)
			(drill 0.1)
			(layers "*.Cu")
			(remove_unused_layers no)
			(net 1 "GND")
			(pinfunction "GND_EP")
			(pintype "power_in")
		)
		(pad "59" thru_hole circle
			(at 2.248 1.327 90)
			(size 0.45 0.45)
			(drill 0.1)
			(layers "*.Cu")
			(remove_unused_layers no)
			(net 1 "GND")
			(pinfunction "GND_EP")
			(pintype "power_in")
		)
	)
)
